# SCM (Grand Teton) — schematic netlist excerpt (pin names and nets, part order shuffled) for the footprints in the layout excerpt that follows; sources: Cadence DE-HDL packaged netlist, KiCad conversion of 12092022_DA0F0TMDCD0_F0T_Management_Board_D_brd_V3_OCP.brd

R491  Q_RES  4.7K 1% EMPTY  pkg 0402LF  page 15 : A = P3V3_RGM ; B = RST_BMC_SRST_N
C16  Q_CAP  10UF 6.3V 20% X6S  pkg C0402  page 20 : A = P1V2_AUX ; B = GND

(kicad_pcb
	(version 20260206)
	(generator "pcbnew")
	(generator_version "10.0")
	(general
		(thickness 1.6)
		(legacy_teardrops no)
	)
	(paper "A4")
	(title_block
		(title "12092022_DA0F0TMDCD0_F0T_Management_Board_D_brd_V3_OCP.brd")
		(comment 1 "Grand Teton / footprints 801-802 of 1440")
	)
	(layers
		(0 "F.Cu" signal "TOP")
		(4 "In1.Cu" signal "GND")
		(6 "In2.Cu" signal "IN1")
		(8 "In3.Cu" signal "GND1")
		(10 "In4.Cu" signal "IN2")
		(12 "In5.Cu" signal "VCC")
		(14 "In6.Cu" signal "VCC1")
		(16 "In7.Cu" signal "IN3")
		(18 "In8.Cu" signal "GND2")
		(20 "In9.Cu" signal "IN4")
		(22 "In10.Cu" signal "GND3")
		(2 "B.Cu" signal "BOTTOM")
		(9 "F.Adhes" user "F.Adhesive")
		(11 "B.Adhes" user "B.Adhesive")
		(13 "F.Paste" user "Package Geometry/Pastemask Top")
		(15 "B.Paste" user "Package Geometry/Pastemask Bottom")
		(5 "F.SilkS" user "Ref Des/Silkscreen Top")
		(7 "B.SilkS" user "Ref Des/Silkscreen Bottom")
		(1 "F.Mask" user "Board Geometry/Soldermask Top")
		(3 "B.Mask" user "Board Geometry/Soldermask Bottom")
		(17 "Dwgs.User" user "User.Drawings")
		(19 "Cmts.User" user "User.Comments")
		(21 "Eco1.User" user "User.Eco1")
		(23 "Eco2.User" user "User.Eco2")
		(25 "Edge.Cuts" user "Board Geometry/Outline")
		(27 "Margin" user)
		(31 "F.CrtYd" user "Package Geometry/Place Bound Top")
		(29 "B.CrtYd" user "Package Geometry/Place Bound Bottom")
		(35 "F.Fab" user "Ref Des/Assembly Top")
		(33 "B.Fab" user "Ref Des/Assembly Bottom")
	)
	(footprint ""
		(layer "B.Cu")
		(at 62.865 -31.369 -90)
		(property "Reference" "R491"
			(at 0 0 90)
			(layer "B.SilkS")
			(hide yes)
			(effects
				(font
					(size 1.27 1.27)
				)
				(justify mirror)
			)
		)
		(property "Value" ""
			(at 0 0 90)
			(layer "B.Fab")
			(effects
				(font
					(size 1.27 1.27)
				)
				(justify mirror)
			)
		)
		(duplicate_pad_numbers_are_jumpers no)
		(fp_line
			(start -0.7874 0.4064)
			(end 0.7874 0.4064)
			(stroke
				(width 0.1524)
				(type default)
			)
			(layer "B.SilkS")
		)
		(fp_line
			(start 0.7874 0.4064)
			(end 0.7874 -0.4064)
			(stroke
				(width 0.1524)
				(type default)
			)
			(layer "B.SilkS")
		)
		(fp_line
			(start -0.7874 -0.4064)
			(end -0.7874 0.4064)
			(stroke
				(width 0.1524)
				(type default)
			)
			(layer "B.SilkS")
		)
		(fp_line
			(start 0.7874 -0.4064)
			(end -0.7874 -0.4064)
			(stroke
				(width 0.1524)
				(type default)
			)
			(layer "B.SilkS")
		)
		(fp_line
			(start -0.67945 0.3048)
			(end -0.120396 0.3048)
			(stroke
				(width 0.1)
				(type default)
			)
			(layer "B.Fab")
		)
		(fp_line
			(start -0.120396 0.3048)
			(end -0.120396 0.2794)
			(stroke
				(width 0.1)
				(type default)
			)
			(layer "B.Fab")
		)
		(fp_line
			(start 0.12065 0.3048)
			(end 0.67945 0.3048)
			(stroke
				(width 0.1)
				(type default)
			)
			(layer "B.Fab")
		)
		(fp_line
			(start 0.67945 0.3048)
			(end 0.67945 -0.305054)
			(stroke
				(width 0.1)
				(type default)
			)
			(layer "B.Fab")
		)
		(fp_line
			(start -0.120396 0.2794)
			(end 0.12065 0.2794)
			(stroke
				(width 0.1)
				(type default)
			)
			(layer "B.Fab")
		)
		(fp_line
			(start 0.12065 0.2794)
			(end 0.12065 0.3048)
			(stroke
				(width 0.1)
				(type default)
			)
			(layer "B.Fab")
		)
		(fp_line
			(start -0.12065 -0.2794)
			(end -0.12065 -0.3048)
			(stroke
				(width 0.1)
				(type default)
			)
			(layer "B.Fab")
		)
		(fp_line
			(start 0.12065 -0.2794)
			(end -0.12065 -0.2794)
			(stroke
				(width 0.1)
				(type default)
			)
			(layer "B.Fab")
		)
		(fp_line
			(start -0.67945 -0.3048)
			(end -0.67945 0.3048)
			(stroke
				(width 0.1)
				(type default)
			)
			(layer "B.Fab")
		)
		(fp_line
			(start -0.12065 -0.3048)
			(end -0.67945 -0.3048)
			(stroke
				(width 0.1)
				(type default)
			)
			(layer "B.Fab")
		)
		(fp_line
			(start 0.12065 -0.305054)
			(end 0.12065 -0.2794)
			(stroke
				(width 0.1)
				(type default)
			)
			(layer "B.Fab")
		)
		(fp_line
			(start 0.67945 -0.305054)
			(end 0.12065 -0.305054)
			(stroke
				(width 0.1)
				(type default)
			)
			(layer "B.Fab")
		)
		(pad "1" smd circle
			(at 0.40005 0 90)
			(size 0 0)
			(layers "B.Cu" "B.Mask" "B.Paste")
			(net "P3V3_RGM")
		)
		(pad "2" smd circle
			(at -0.40005 0 90)
			(size 0 0)
			(layers "B.Cu" "B.Mask" "B.Paste")
			(net "RST_BMC_SRST_N")
		)
	)
	(footprint ""
		(layer "B.Cu")
		(at 73.516998 -47.730156)
		(property "Reference" "C16"
			(at 0 0 0)
			(layer "B.SilkS")
			(hide yes)
			(effects
				(font
					(size 1.27 1.27)
				)
				(justify mirror)
			)
		)
		(property "Value" ""
			(at 0 0 0)
			(layer "B.Fab")
			(effects
				(font
					(size 1.27 1.27)
				)
				(justify mirror)
			)
		)
		(duplicate_pad_numbers_are_jumpers no)
		(fp_line
			(start -0.7874 -0.4064)
			(end -0.7874 0.4064)
			(stroke
				(width 0.1524)
				(type default)
			)
			(layer "B.SilkS")
		)
		(fp_line
			(start -0.7874 0.4064)
			(end 0.7874 0.4064)
			(stroke
				(width 0.1524)
				(type default)
			)
			(layer "B.SilkS")
		)
		(fp_line
			(start 0.7874 -0.4064)
			(end -0.7874 -0.4064)
			(stroke
				(width 0.1524)
				(type default)
			)
			(layer "B.SilkS")
		)
		(fp_line
			(start 0.7874 0.4064)
			(end 0.7874 -0.4064)
			(stroke
				(width 0.1524)
				(type default)
			)
			(layer "B.SilkS")
		)
		(fp_line
			(start -0.67945 -0.3048)
			(end -0.67945 0.3048)
			(stroke
				(width 0.1)
				(type default)
			)
			(layer "B.Fab")
		)
		(fp_line
			(start -0.67945 0.3048)
			(end -0.120396 0.3048)
			(stroke
				(width 0.1)
				(type default)
			)
			(layer "B.Fab")
		)
		(fp_line
			(start -0.12065 -0.3048)
			(end -0.67945 -0.3048)
			(stroke
				(width 0.1)
				(type default)
			)
			(layer "B.Fab")
		)
		(fp_line
			(start -0.12065 -0.2794)
			(end -0.12065 -0.3048)
			(stroke
				(width 0.1)
				(type default)
			)
			(layer "B.Fab")
		)
		(fp_line
			(start -0.120396 0.2794)
			(end 0.12065 0.2794)
			(stroke
				(width 0.1)
				(type default)
			)
			(layer "B.Fab")
		)
		(fp_line
			(start -0.120396 0.3048)
			(end -0.120396 0.2794)
			(stroke
				(width 0.1)
				(type default)
			)
			(layer "B.Fab")
		)
		(fp_line
			(start 0.12065 -0.305054)
			(end 0.12065 -0.2794)
			(stroke
				(width 0.1)
				(type default)
			)
			(layer "B.Fab")
		)
		(fp_line
			(start 0.12065 -0.2794)
			(end -0.12065 -0.2794)
			(stroke
				(width 0.1)
				(type default)
			)
			(layer "B.Fab")
		)
		(fp_line
			(start 0.12065 0.2794)
			(end 0.12065 0.3048)
			(stroke
				(width 0.1)
				(type default)
			)
			(layer "B.Fab")
		)
		(fp_line
			(start 0.12065 0.3048)
			(end 0.67945 0.3048)
			(stroke
				(width 0.1)
				(type default)
			)
			(layer "B.Fab")
		)
		(fp_line
			(start 0.67945 -0.305054)
			(end 0.12065 -0.305054)
			(stroke
				(width 0.1)
				(type default)
			)
			(layer "B.Fab")
		)
		(fp_line
			(start 0.67945 0.3048)
			(end 0.67945 -0.305054)
			(stroke
				(width 0.1)
				(type default)
			)
			(layer "B.Fab")
		)
		(pad "1" smd circle
			(at 0.40005 0 180)
			(size 0 0)
			(layers "B.Cu" "B.Mask" "B.Paste")
			(net "P1V2_AUX")
		)
		(pad "2" smd circle
			(at -0.40005 0 180)
			(size 0 0)
			(layers "B.Cu" "B.Mask" "B.Paste")
			(net "GND")
		)
	)
)
